(kicad_pcb
	(version 20241229)
	(generator "pcbnew")
	(generator_version "9.0")
	(general
		(thickness 1.294)
		(legacy_teardrops no)
	)
	(paper "A3")
	(title_block
		(title "Kintex 410T devboard")
		(date "2024-04-03")
		(rev "1.1.2")
		(comment 9 "footprints 655-660 of 975")
	)
	(layers
		(0 "F.Cu" mixed)
		(4 "In1.Cu" power)
		(6 "In2.Cu" power)
		(8 "In3.Cu" mixed)
		(10 "In4.Cu" power)
		(12 "In5.Cu" mixed)
		(14 "In6.Cu" power)
		(16 "In7.Cu" mixed)
		(18 "In8.Cu" power)
		(2 "B.Cu" mixed)
		(9 "F.Adhes" user "F.Adhesive")
		(11 "B.Adhes" user "B.Adhesive")
		(13 "F.Paste" user)
		(15 "B.Paste" user)
		(5 "F.SilkS" user "F.Silkscreen")
		(7 "B.SilkS" user "B.Silkscreen")
		(1 "F.Mask" user)
		(3 "B.Mask" user)
		(17 "Dwgs.User" user "User.Drawings")
		(19 "Cmts.User" user "User.Comments")
		(21 "Eco1.User" user "User.Eco1")
		(23 "Eco2.User" user "User.Eco2")
		(25 "Edge.Cuts" user)
		(27 "Margin" user)
		(31 "F.CrtYd" user "F.Courtyard")
		(29 "B.CrtYd" user "B.Courtyard")
		(35 "F.Fab" user)
		(33 "B.Fab" user)
	)
	(footprint "antmicro-footprints:C_0603_1608Metric"
		(layer "B.Cu")
		(at 205.05 130 180)
		(descr "Capacitor SMD 0603")
		(tags "capacitor 0603")
		(property "Reference" "C382"
			(at -29.725 28.375 0)
			(layer "B.SilkS")
			(effects
				(font
					(size 0.7 0.7)
					(thickness 0.15)
				)
				(justify left bottom mirror)
			)
		)
		(property "Value" "C_47u_0603"
			(at 0 -1.6 0)
			(layer "B.Fab")
			(effects
				(font
					(size 0.7 0.7)
					(thickness 0.15)
				)
				(justify left bottom mirror)
			)
		)
		(property "Description" "SMD Multilayer Ceramic Capacitor, 47 µF, 6.3 V, 0603 [1608 Metric], ± 20%, X5R, GRM Series"
			(at 0 0 180)
			(layer "F.Fab")
			(hide yes)
			(effects
				(font
					(size 1.27 1.27)
					(thickness 0.15)
				)
			)
		)
		(property "Author" "Antmicro"
			(at 410.1 260 0)
			(layer "B.Fab")
			(hide yes)
			(effects
				(font
					(size 1 1)
					(thickness 0.15)
				)
				(justify mirror)
			)
		)
		(property "Dielectric" ""
			(at 410.1 260 0)
			(layer "B.Fab")
			(hide yes)
			(effects
				(font
					(size 1 1)
					(thickness 0.15)
				)
				(justify mirror)
			)
		)
		(property "License" "Apache-2.0"
			(at 410.1 260 0)
			(layer "B.Fab")
			(hide yes)
			(effects
				(font
					(size 1 1)
					(thickness 0.15)
				)
				(justify mirror)
			)
		)
		(property "MPN" "GRM188R60J476ME15D"
			(at 410.1 260 0)
			(layer "B.Fab")
			(hide yes)
			(effects
				(font
					(size 1 1)
					(thickness 0.15)
				)
				(justify mirror)
			)
		)
		(property "Manufacturer" "Murata"
			(at 410.1 260 0)
			(layer "B.Fab")
			(hide yes)
			(effects
				(font
					(size 1 1)
					(thickness 0.15)
				)
				(justify mirror)
			)
		)
		(property "Val" "47u"
			(at 410.1 260 0)
			(layer "B.Fab")
			(hide yes)
			(effects
				(font
					(size 1 1)
					(thickness 0.15)
				)
				(justify mirror)
			)
		)
		(property "Voltage" ""
			(at 410.1 260 0)
			(layer "B.Fab")
			(hide yes)
			(effects
				(font
					(size 1 1)
					(thickness 0.15)
				)
				(justify mirror)
			)
		)
		(sheetname "FPGA supply")
		(sheetfile "fpga-supply.kicad_sch")
		(attr smd)
		(fp_line
			(start -0.15 0.4)
			(end 0.15 0.4)
			(stroke
				(width 0.15)
				(type solid)
			)
			(layer "B.SilkS")
		)
		(fp_line
			(start -0.15 -0.4)
			(end 0.15 -0.4)
			(stroke
				(width 0.15)
				(type solid)
			)
			(layer "B.SilkS")
		)
		(fp_rect
			(start -1.25 0.65)
			(end 1.25 -0.65)
			(stroke
				(width 0.05)
				(type solid)
			)
			(fill no)
			(layer "B.CrtYd")
		)
		(fp_rect
			(start -0.8 0.4)
			(end 0.8 -0.4)
			(stroke
				(width 0.15)
				(type solid)
			)
			(fill no)
			(layer "B.Fab")
		)
		(pad "1" smd roundrect
			(at -0.7 0 180)
			(size 0.8 1)
			(layers "B.Cu" "B.Mask" "B.Paste")
			(roundrect_rratio 0.2)
			(net 1 "GND")
			(pintype "passive")
		)
		(pad "2" smd roundrect
			(at 0.7 0 180)
			(size 0.8 1)
			(layers "B.Cu" "B.Mask" "B.Paste")
			(roundrect_rratio 0.2)
			(net 650 "+1V0")
			(pintype "passive")
		)
	)
	(footprint "antmicro-footprints:C_0402_1005Metric"
		(layer "B.Cu")
		(at 192.01 141.5 180)
		(descr "Capacitor SMD 0402")
		(tags "capacitor SMD 0402")
		(property "Reference" "C374"
			(at -1.875 0.475 0)
			(layer "B.SilkS")
			(effects
				(font
					(size 0.7 0.7)
					(thickness 0.15)
				)
				(justify left bottom mirror)
			)
		)
		(property "Value" "C_100n_0402"
			(at 0 -1.169 0)
			(layer "B.Fab")
			(effects
				(font
					(size 0.7 0.7)
					(thickness 0.15)
				)
				(justify left bottom mirror)
			)
		)
		(property "Description" "SMD Multilayer Ceramic Capacitor, 0.1 µF, 50 V, 0402 [1005 Metric], ± 10%, X5R, GRM Series"
			(at 0 0 180)
			(layer "F.Fab")
			(hide yes)
			(effects
				(font
					(size 1.27 1.27)
					(thickness 0.15)
				)
			)
		)
		(property "Author" "Antmicro"
			(at 384.02 283 0)
			(layer "B.Fab")
			(hide yes)
			(effects
				(font
					(size 1 1)
					(thickness 0.15)
				)
				(justify mirror)
			)
		)
		(property "Dielectric" "X5R"
			(at 384.02 283 0)
			(layer "B.Fab")
			(hide yes)
			(effects
				(font
					(size 1 1)
					(thickness 0.15)
				)
				(justify mirror)
			)
		)
		(property "License" "Apache-2.0"
			(at 384.02 283 0)
			(layer "B.Fab")
			(hide yes)
			(effects
				(font
					(size 1 1)
					(thickness 0.15)
				)
				(justify mirror)
			)
		)
		(property "MPN" "GRM155R61H104KE14D"
			(at 384.02 283 0)
			(layer "B.Fab")
			(hide yes)
			(effects
				(font
					(size 1 1)
					(thickness 0.15)
				)
				(justify mirror)
			)
		)
		(property "Manufacturer" "Murata"
			(at 384.02 283 0)
			(layer "B.Fab")
			(hide yes)
			(effects
				(font
					(size 1 1)
					(thickness 0.15)
				)
				(justify mirror)
			)
		)
		(property "Val" "100n"
			(at 384.02 283 0)
			(layer "B.Fab")
			(hide yes)
			(effects
				(font
					(size 1 1)
					(thickness 0.15)
				)
				(justify mirror)
			)
		)
		(property "Voltage" "50V"
			(at 384.02 283 0)
			(layer "B.Fab")
			(hide yes)
			(effects
				(font
					(size 1 1)
					(thickness 0.15)
				)
				(justify mirror)
			)
		)
		(sheetname "FPGA Bank 33 & 34")
		(sheetfile "fpga-bank-33-34.kicad_sch")
		(attr smd)
		(fp_rect
			(start -0.925 0.47)
			(end 0.925 -0.47)
			(stroke
				(width 0.05)
				(type default)
			)
			(fill no)
			(layer "B.CrtYd")
		)
		(fp_line
			(start 0.504 0.25)
			(end 0.504 -0.248)
			(stroke
				(width 0.15)
				(type solid)
			)
			(layer "B.Fab")
		)
		(fp_line
			(start 0.504 -0.248)
			(end -0.494 -0.248)
			(stroke
				(width 0.15)
				(type solid)
			)
			(layer "B.Fab")
		)
		(fp_line
			(start -0.494 0.25)
			(end 0.504 0.25)
			(stroke
				(width 0.15)
				(type solid)
			)
			(layer "B.Fab")
		)
		(fp_line
			(start -0.494 -0.248)
			(end -0.494 0.25)
			(stroke
				(width 0.15)
				(type solid)
			)
			(layer "B.Fab")
		)
		(pad "1" smd roundrect
			(at -0.48 0 180)
			(size 0.59 0.64)
			(layers "B.Cu" "B.Mask" "B.Paste")
			(roundrect_rratio 0.25)
			(net 1 "GND")
			(pintype "passive")
		)
		(pad "2" smd roundrect
			(at 0.48 0 180)
			(size 0.59 0.64)
			(layers "B.Cu" "B.Mask" "B.Paste")
			(roundrect_rratio 0.25)
			(net 11 "+0V675_VREF")
			(pintype "passive")
		)
	)
	(footprint "antmicro-footprints:NetTie-2_SMD_Pad0.127mm"
		(layer "B.Cu")
		(at 193.59 145.72)
		(descr "Net tie, 2 pin, 0.127mm  SMD pads")
		(tags "net tie")
		(property "Reference" "NT36"
			(at -0.128 1.345 180)
			(layer "B.SilkS")
			(hide yes)
			(effects
				(font
					(size 0.7 0.7)
					(thickness 0.15)
				)
				(justify left bottom mirror)
			)
		)
		(property "Value" "Net-Tie_2"
			(at 0 -1.199 180)
			(layer "B.Fab")
			(effects
				(font
					(size 0.7 0.7)
					(thickness 0.15)
				)
				(justify left bottom mirror)
			)
		)
		(property "Description" "Net tie, 2 pins"
			(at 0 0 0)
			(layer "F.Fab")
			(hide yes)
			(effects
				(font
					(size 1.27 1.27)
					(thickness 0.15)
				)
			)
		)
		(property "Author" "Antmicro"
			(at 0 0 0)
			(layer "B.Fab")
			(hide yes)
			(effects
				(font
					(size 1 1)
					(thickness 0.15)
				)
				(justify mirror)
			)
		)
		(property "License" "Apache-2.0"
			(at 0 0 0)
			(layer "B.Fab")
			(hide yes)
			(effects
				(font
					(size 1 1)
					(thickness 0.15)
				)
				(justify mirror)
			)
		)
		(property "MPN" ""
			(at 0 0 0)
			(layer "B.Fab")
			(hide yes)
			(effects
				(font
					(size 1 1)
					(thickness 0.15)
				)
				(justify mirror)
			)
		)
		(property "Manufacturer" ""
			(at 0 0 0)
			(layer "B.Fab")
			(hide yes)
			(effects
				(font
					(size 1 1)
					(thickness 0.15)
				)
				(justify mirror)
			)
		)
		(sheetname "DC-DC Converters")
		(sheetfile "dc-dc.kicad_sch")
		(attr exclude_from_pos_files)
		(net_tie_pad_groups "1, 2")
		(fp_poly
			(pts
				(xy -0.0635 0.0635) (xy 0.0625 0.0635) (xy 0.0625 -0.0635) (xy -0.0635 -0.0635)
			)
			(stroke
				(width 0)
				(type solid)
			)
			(fill yes)
			(layer "B.Cu")
		)
		(pad "1" smd roundrect
			(at -0.127 0 180)
			(size 0.127 0.127)
			(layers "B.Cu")
			(roundrect_rratio 0.5)
			(chamfer_ratio 0)
			(chamfer top_left bottom_left)
			(net 1224 "/DC-DC Converters/SENSE_1V8_P")
			(pinfunction "1")
			(pintype "passive")
		)
		(pad "2" smd roundrect
			(at 0.126 0)
			(size 0.127 0.127)
			(layers "B.Cu")
			(roundrect_rratio 0.5)
			(chamfer_ratio 0)
			(chamfer top_left bottom_left)
			(net 26 "+1V8")
			(pinfunction "2")
			(pintype "passive")
		)
	)
	(footprint "antmicro-footprints:C_0402_1005Metric"
		(layer "B.Cu")
		(at 208.5 121 90)
		(descr "Capacitor SMD 0402")
		(tags "capacitor SMD 0402")
		(property "Reference" "C39"
			(at 1.1 1.225 270)
			(layer "B.SilkS")
			(effects
				(font
					(size 0.7 0.7)
					(thickness 0.15)
				)
				(justify left bottom mirror)
			)
		)
		(property "Value" "C_100n_0402"
			(at 0 -1.169 270)
			(layer "B.Fab")
			(effects
				(font
					(size 0.7 0.7)
					(thickness 0.15)
				)
				(justify left bottom mirror)
			)
		)
		(property "Description" "SMD Multilayer Ceramic Capacitor, 0.1 µF, 50 V, 0402 [1005 Metric], ± 10%, X5R, GRM Series"
			(at 0 0 90)
			(layer "F.Fab")
			(hide yes)
			(effects
				(font
					(size 1.27 1.27)
					(thickness 0.15)
				)
			)
		)
		(property "Author" "Antmicro"
			(at 329.5 -87.5 0)
			(layer "B.Fab")
			(hide yes)
			(effects
				(font
					(size 1 1)
					(thickness 0.15)
				)
				(justify mirror)
			)
		)
		(property "Dielectric" "X5R"
			(at 329.5 -87.5 0)
			(layer "B.Fab")
			(hide yes)
			(effects
				(font
					(size 1 1)
					(thickness 0.15)
				)
				(justify mirror)
			)
		)
		(property "License" "Apache-2.0"
			(at 329.5 -87.5 0)
			(layer "B.Fab")
			(hide yes)
			(effects
				(font
					(size 1 1)
					(thickness 0.15)
				)
				(justify mirror)
			)
		)
		(property "MPN" "GRM155R61H104KE14D"
			(at 329.5 -87.5 0)
			(layer "B.Fab")
			(hide yes)
			(effects
				(font
					(size 1 1)
					(thickness 0.15)
				)
				(justify mirror)
			)
		)
		(property "Manufacturer" "Murata"
			(at 329.5 -87.5 0)
			(layer "B.Fab")
			(hide yes)
			(effects
				(font
					(size 1 1)
					(thickness 0.15)
				)
				(justify mirror)
			)
		)
		(property "Val" "100n"
			(at 329.5 -87.5 0)
			(layer "B.Fab")
			(hide yes)
			(effects
				(font
					(size 1 1)
					(thickness 0.15)
				)
				(justify mirror)
			)
		)
		(property "Voltage" "50V"
			(at 329.5 -87.5 0)
			(layer "B.Fab")
			(hide yes)
			(effects
				(font
					(size 1 1)
					(thickness 0.15)
				)
				(justify mirror)
			)
		)
		(sheetname "FPGA Bank 16 & 17")
		(sheetfile "fpga-bank-16-17.kicad_sch")
		(attr smd)
		(fp_rect
			(start -0.925 0.47)
			(end 0.925 -0.47)
			(stroke
				(width 0.05)
				(type default)
			)
			(fill no)
			(layer "B.CrtYd")
		)
		(fp_line
			(start 0.504 -0.248)
			(end -0.494 -0.248)
			(stroke
				(width 0.15)
				(type solid)
			)
			(layer "B.Fab")
		)
		(fp_line
			(start -0.494 -0.248)
			(end -0.494 0.25)
			(stroke
				(width 0.15)
				(type solid)
			)
			(layer "B.Fab")
		)
		(fp_line
			(start 0.504 0.25)
			(end 0.504 -0.248)
			(stroke
				(width 0.15)
				(type solid)
			)
			(layer "B.Fab")
		)
		(fp_line
			(start -0.494 0.25)
			(end 0.504 0.25)
			(stroke
				(width 0.15)
				(type solid)
			)
			(layer "B.Fab")
		)
		(pad "1" smd roundrect
			(at -0.48 0 90)
			(size 0.59 0.64)
			(layers "B.Cu" "B.Mask" "B.Paste")
			(roundrect_rratio 0.25)
			(net 1 "GND")
			(pintype "passive")
		)
		(pad "2" smd roundrect
			(at 0.48 0 90)
			(size 0.59 0.64)
			(layers "B.Cu" "B.Mask" "B.Paste")
			(roundrect_rratio 0.25)
			(net 3 "VCC_USR_B")
			(pintype "passive")
		)
	)
	(footprint "antmicro-footprints:R_Array_4x0201_Panasonic_EXB18V"
		(layer "B.Cu")
		(at 165.999999 146.199999 180)
		(property "Reference" "R15"
			(at 6.474999 -6.125001 0)
			(layer "B.SilkS")
			(effects
				(font
					(size 0.7 0.7)
					(thickness 0.15)
				)
				(justify right bottom mirror)
			)
		)
		(property "Value" "4x39R_0201_array"
			(at -1.1 -1.8 0)
			(layer "B.Fab")
			(effects
				(font
					(size 0.7 0.7)
					(thickness 0.15)
				)
				(justify left bottom mirror)
			)
		)
		(property "Description" "Fixed Network Resistor, 39 ohm, Isolated, 4 Resistors, 0502 [1406 Metric], Flat, ± 5%"
			(at 0 0 180)
			(layer "F.Fab")
			(hide yes)
			(effects
				(font
					(size 1.27 1.27)
					(thickness 0.15)
				)
			)
		)
		(property "Author" "Antmicro"
			(at 331.999998 292.399998 0)
			(layer "B.Fab")
			(hide yes)
			(effects
				(font
					(size 1 1)
					(thickness 0.15)
				)
				(justify mirror)
			)
		)
		(property "License" "Apache-2.0"
			(at 331.999998 292.399998 0)
			(layer "B.Fab")
			(hide yes)
			(effects
				(font
					(size 1 1)
					(thickness 0.15)
				)
				(justify mirror)
			)
		)
		(property "MPN" "EXB-18V390JX"
			(at 331.999998 292.399998 0)
			(layer "B.Fab")
			(hide yes)
			(effects
				(font
					(size 1 1)
					(thickness 0.15)
				)
				(justify mirror)
			)
		)
		(property "Manufacturer" "Panasonic"
			(at 331.999998 292.399998 0)
			(layer "B.Fab")
			(hide yes)
			(effects
				(font
					(size 1 1)
					(thickness 0.15)
				)
				(justify mirror)
			)
		)
		(property "Val" "4x39R_0201"
			(at 331.999998 292.399998 0)
			(layer "B.Fab")
			(hide yes)
			(effects
				(font
					(size 1 1)
					(thickness 0.15)
				)
				(justify mirror)
			)
		)
		(sheetname "DRAM + SRAM")
		(sheetfile "ram.kicad_sch")
		(attr smd)
		(fp_line
			(start 0.8 0.45)
			(end 0.8 -0.45)
			(stroke
				(width 0.12)
				(type solid)
			)
			(layer "B.SilkS")
		)
		(fp_line
			(start -0.8 0.45)
			(end -0.8 -0.45)
			(stroke
				(width 0.12)
				(type solid)
			)
			(layer "B.SilkS")
		)
		(fp_rect
			(start -0.898 0.66)
			(end 0.898 -0.65)
			(stroke
				(width 0.05)
				(type solid)
			)
			(fill no)
			(layer "B.CrtYd")
		)
		(pad "1" smd roundrect
			(at -0.6 -0.298 180)
			(size 0.2 0.4)
			(layers "B.Cu" "B.Mask" "B.Paste")
			(roundrect_rratio 0.25)
			(net 543 "/DRAM + SRAM/DDR.A12")
			(pinfunction "R1.1")
			(pintype "passive")
		)
		(pad "2" smd roundrect
			(at -0.202 -0.298 180)
			(size 0.2 0.4)
			(layers "B.Cu" "B.Mask" "B.Paste")
			(roundrect_rratio 0.25)
			(net 548 "/DRAM + SRAM/DDR.BA1")
			(pinfunction "R2.1")
			(pintype "passive")
		)
		(pad "3" smd roundrect
			(at 0.2 -0.298 180)
			(size 0.2 0.4)
			(layers "B.Cu" "B.Mask" "B.Paste")
			(roundrect_rratio 0.25)
			(net 532 "/DRAM + SRAM/DDR.A1")
			(pinfunction "R3.1")
			(pintype "passive")
		)
		(pad "4" smd roundrect
			(at 0.598 -0.298 180)
			(size 0.2 0.4)
			(layers "B.Cu" "B.Mask" "B.Paste")
			(roundrect_rratio 0.25)
			(net 535 "/DRAM + SRAM/DDR.A4")
			(pinfunction "R4.1")
			(pintype "passive")
		)
		(pad "5" smd roundrect
			(at 0.598 0.3 180)
			(size 0.2 0.4)
			(layers "B.Cu" "B.Mask" "B.Paste")
			(roundrect_rratio 0.25)
			(net 7 "+0V675_VTT")
			(pinfunction "R4.2")
			(pintype "passive")
		)
		(pad "6" smd roundrect
			(at 0.2 0.3 180)
			(size 0.2 0.4)
			(layers "B.Cu" "B.Mask" "B.Paste")
			(roundrect_rratio 0.25)
			(net 7 "+0V675_VTT")
			(pinfunction "R3.2")
			(pintype "passive")
		)
		(pad "7" smd roundrect
			(at -0.202 0.3 180)
			(size 0.2 0.4)
			(layers "B.Cu" "B.Mask" "B.Paste")
			(roundrect_rratio 0.25)
			(net 7 "+0V675_VTT")
			(pinfunction "R2.2")
			(pintype "passive")
		)
		(pad "8" smd roundrect
			(at -0.6 0.3 180)
			(size 0.2 0.4)
			(layers "B.Cu" "B.Mask" "B.Paste")
			(roundrect_rratio 0.25)
			(net 7 "+0V675_VTT")
			(pinfunction "R1.2")
			(pintype "passive")
		)
	)
	(footprint "antmicro-footprints:C_0402_1005Metric"
		(layer "B.Cu")
		(at 196.4 133.2)
		(descr "Capacitor SMD 0402")
		(tags "capacitor SMD 0402")
		(property "Reference" "C73"
			(at 25.15 -28.025 180)
			(layer "B.SilkS")
			(effects
				(font
					(size 0.7 0.7)
					(thickness 0.15)
				)
				(justify left bottom mirror)
			)
		)
		(property "Value" "C_100n_0402"
			(at 0 -1.169 180)
			(layer "B.Fab")
			(effects
				(font
					(size 0.7 0.7)
					(thickness 0.15)
				)
				(justify left bottom mirror)
			)
		)
		(property "Description" "SMD Multilayer Ceramic Capacitor, 0.1 µF, 50 V, 0402 [1005 Metric], ± 10%, X5R, GRM Series"
			(at 0 0 0)
			(layer "F.Fab")
			(hide yes)
			(effects
				(font
					(size 1.27 1.27)
					(thickness 0.15)
				)
			)
		)
		(property "Author" "Antmicro"
			(at 0 0 0)
			(layer "B.Fab")
			(hide yes)
			(effects
				(font
					(size 1 1)
					(thickness 0.15)
				)
				(justify mirror)
			)
		)
		(property "Dielectric" "X5R"
			(at 0 0 0)
			(layer "B.Fab")
			(hide yes)
			(effects
				(font
					(size 1 1)
					(thickness 0.15)
				)
				(justify mirror)
			)
		)
		(property "License" "Apache-2.0"
			(at 0 0 0)
			(layer "B.Fab")
			(hide yes)
			(effects
				(font
					(size 1 1)
					(thickness 0.15)
				)
				(justify mirror)
			)
		)
		(property "MPN" "GRM155R61H104KE14D"
			(at 0 0 0)
			(layer "B.Fab")
			(hide yes)
			(effects
				(font
					(size 1 1)
					(thickness 0.15)
				)
				(justify mirror)
			)
		)
		(property "Manufacturer" "Murata"
			(at 0 0 0)
			(layer "B.Fab")
			(hide yes)
			(effects
				(font
					(size 1 1)
					(thickness 0.15)
				)
				(justify mirror)
			)
		)
		(property "Val" "100n"
			(at 0 0 0)
			(layer "B.Fab")
			(hide yes)
			(effects
				(font
					(size 1 1)
					(thickness 0.15)
				)
				(justify mirror)
			)
		)
		(property "Voltage" "50V"
			(at 0 0 0)
			(layer "B.Fab")
			(hide yes)
			(effects
				(font
					(size 1 1)
					(thickness 0.15)
				)
				(justify mirror)
			)
		)
		(sheetname "FPGA supply")
		(sheetfile "fpga-supply.kicad_sch")
		(attr smd)
		(fp_rect
			(start -0.925 0.47)
			(end 0.925 -0.47)
			(stroke
				(width 0.05)
				(type default)
			)
			(fill no)
			(layer "B.CrtYd")
		)
		(fp_line
			(start -0.494 -0.248)
			(end -0.494 0.25)
			(stroke
				(width 0.15)
				(type solid)
			)
			(layer "B.Fab")
		)
		(fp_line
			(start -0.494 0.25)
			(end 0.504 0.25)
			(stroke
				(width 0.15)
				(type solid)
			)
			(layer "B.Fab")
		)
		(fp_line
			(start 0.504 -0.248)
			(end -0.494 -0.248)
			(stroke
				(width 0.15)
				(type solid)
			)
			(layer "B.Fab")
		)
		(fp_line
			(start 0.504 0.25)
			(end 0.504 -0.248)
			(stroke
				(width 0.15)
				(type solid)
			)
			(layer "B.Fab")
		)
		(pad "1" smd roundrect
			(at -0.48 0)
			(size 0.59 0.64)
			(layers "B.Cu" "B.Mask" "B.Paste")
			(roundrect_rratio 0.25)
			(net 1 "GND")
			(pintype "passive")
		)
		(pad "2" smd roundrect
			(at 0.48 0)
			(size 0.59 0.64)
			(layers "B.Cu" "B.Mask" "B.Paste")
			(roundrect_rratio 0.25)
			(net 26 "+1V8")
			(pintype "passive")
		)
	)
)
